# BASEBOARD_FAB2 (Tioga Pass) — schematic netlist excerpt (pin names and nets, part order shuffled) for the footprints in the layout excerpt that follows; sources: Cadence DE-HDL packaged netlist, KiCad conversion of Wiwynn_Tioga_Pass_MB.brd

R9G28  RES  0.0 5% CHIP  pkg 0402  page 152 : A = H_CPU1_KLM_MEMHOT_LVT3_R_N ; B = H_CPU1_MEMKLM_MEMHOT_LVT3_K_N
R1L13  RES  1.00K 1% CHIP  pkg 0402  page 111 : A = XDP_SYSPWROK ; B = P3V3_STBY
C2M9  CAP_A  1.0UF 6.3V 10% X6S  pkg 0402V  page 127 : A = P1V05_PCH_STBY_WM26_PLL ; B = GND

(kicad_pcb
	(version 20260206)
	(generator "pcbnew")
	(generator_version "10.0")
	(general
		(thickness 1.6)
		(legacy_teardrops no)
	)
	(paper "A4")
	(title_block
		(title "Wiwynn_Tioga_Pass_MB.brd")
		(comment 1 "Tioga Pass / footprints 2534-2536 of 4770")
	)
	(layers
		(0 "F.Cu" signal "TOP")
		(4 "In1.Cu" signal "L2GND")
		(6 "In2.Cu" signal "L3")
		(8 "In3.Cu" signal "L4GND")
		(10 "In4.Cu" signal "L5")
		(12 "In5.Cu" signal "L6GND")
		(14 "In6.Cu" signal "L7VCC")
		(16 "In7.Cu" signal "L8VCC")
		(18 "In8.Cu" signal "L9GND")
		(20 "In9.Cu" signal "L10")
		(22 "In10.Cu" signal "L11GND")
		(24 "In11.Cu" signal "L12")
		(26 "In12.Cu" signal "L13GND")
		(2 "B.Cu" signal "BOTTOM")
		(9 "F.Adhes" user "F.Adhesive")
		(11 "B.Adhes" user "B.Adhesive")
		(13 "F.Paste" user "Package Geometry/Pastemask Top")
		(15 "B.Paste" user "Package Geometry/Pastemask Bottom")
		(5 "F.SilkS" user "Ref Des/Silkscreen Top")
		(7 "B.SilkS" user "Ref Des/Silkscreen Bottom")
		(1 "F.Mask" user "Board Geometry/Soldermask Top")
		(3 "B.Mask" user "Board Geometry/Soldermask Bottom")
		(17 "Dwgs.User" user "User.Drawings")
		(19 "Cmts.User" user "User.Comments")
		(21 "Eco1.User" user "User.Eco1")
		(23 "Eco2.User" user "User.Eco2")
		(25 "Edge.Cuts" user "Board Geometry/Outline")
		(27 "Margin" user)
		(31 "F.CrtYd" user "Package Geometry/Place Bound Top")
		(29 "B.CrtYd" user "Package Geometry/Place Bound Bottom")
		(35 "F.Fab" user "Ref Des/Assembly Top")
		(33 "B.Fab" user "Ref Des/Assembly Bottom")
	)
	(footprint ""
		(layer "B.Cu")
		(at 407.0858 -119.4816)
		(property "Reference" "C2M9"
			(at 0 0 0)
			(layer "B.SilkS")
			(hide yes)
			(effects
				(font
					(size 1.27 1.27)
				)
				(justify mirror)
			)
		)
		(property "Value" ""
			(at 0 0 0)
			(layer "B.Fab")
			(effects
				(font
					(size 1.27 1.27)
				)
				(justify mirror)
			)
		)
		(duplicate_pad_numbers_are_jumpers no)
		(fp_poly
			(pts
				(xy -0.3048 -0.1016) (xy -0.3048 0.9906) (xy 0.3048 0.9906) (xy 0.3048 -0.1016)
			)
			(stroke
				(width 0)
				(type default)
			)
			(fill no)
			(layer "B.CrtYd")
		)
		(fp_line
			(start -0.3048 -0.1016)
			(end 0.3048 -0.1016)
			(stroke
				(width 0.1)
				(type default)
			)
			(layer "B.Fab")
		)
		(fp_line
			(start -0.3048 0.9906)
			(end -0.3048 -0.1016)
			(stroke
				(width 0.1)
				(type default)
			)
			(layer "B.Fab")
		)
		(fp_line
			(start 0.3048 -0.1016)
			(end 0.3048 0.9906)
			(stroke
				(width 0.1)
				(type default)
			)
			(layer "B.Fab")
		)
		(fp_line
			(start 0.3048 0.9906)
			(end -0.3048 0.9906)
			(stroke
				(width 0.1)
				(type default)
			)
			(layer "B.Fab")
		)
		(pad "1" smd rect
			(at 0 0 180)
			(size 0.508 0.508)
			(layers "B.Cu" "B.Mask" "B.Paste")
			(net "P1V05_PCH_STBY_WM26_PLL")
		)
		(pad "2" smd rect
			(at 0 0.889 180)
			(size 0.508 0.508)
			(layers "B.Cu" "B.Mask" "B.Paste")
			(net "GND")
		)
		(zone
			(layer "B.Cu")
			(hatch none 0.5)
			(connect_pads
				(clearance 0)
			)
			(min_thickness 0.25)
			(keepout
				(tracks allowed)
				(vias not_allowed)
				(pads allowed)
				(copperpour not_allowed)
				(footprints allowed)
			)
			(placement
				(enabled no)
				(sheetname "")
			)
			(fill
				(thermal_gap 0.5)
				(thermal_bridge_width 0.5)
				(island_removal_mode 0)
			)
			(polygon
				(pts
					(xy 407.3398 -119.2276) (xy 406.8318 -119.2276) (xy 406.8318 -118.8466) (xy 407.3398 -118.8466)
				)
			)
		)
		(zone
			(layer "B.Cu")
			(hatch none 0.5)
			(connect_pads
				(clearance 0)
			)
			(min_thickness 0.25)
			(keepout
				(tracks not_allowed)
				(vias allowed)
				(pads allowed)
				(copperpour not_allowed)
				(footprints allowed)
			)
			(placement
				(enabled no)
				(sheetname "")
			)
			(fill
				(thermal_gap 0.5)
				(thermal_bridge_width 0.5)
				(island_removal_mode 0)
			)
			(polygon
				(pts
					(xy 407.3398 -118.8466) (xy 406.8318 -118.8466) (xy 406.8318 -119.2276) (xy 407.3398 -119.2276)
				)
			)
		)
	)
	(footprint ""
		(layer "B.Cu")
		(at 433.7685 -17.399 90)
		(property "Reference" "R9G28"
			(at 0 0 90)
			(layer "B.SilkS")
			(hide yes)
			(effects
				(font
					(size 1.27 1.27)
				)
				(justify mirror)
			)
		)
		(property "Value" ""
			(at 0 0 90)
			(layer "B.Fab")
			(effects
				(font
					(size 1.27 1.27)
				)
				(justify mirror)
			)
		)
		(duplicate_pad_numbers_are_jumpers no)
		(fp_poly
			(pts
				(xy 0.2794 -0.1016) (xy -0.2794 -0.1016) (xy -0.2794 0.9906) (xy 0.2794 0.9906)
			)
			(stroke
				(width 0)
				(type default)
			)
			(fill no)
			(layer "B.CrtYd")
		)
		(fp_line
			(start 0.2794 -0.1016)
			(end 0.2794 0.9906)
			(stroke
				(width 0.1)
				(type default)
			)
			(layer "B.Fab")
		)
		(fp_line
			(start -0.2794 -0.1016)
			(end 0.2794 -0.1016)
			(stroke
				(width 0.1)
				(type default)
			)
			(layer "B.Fab")
		)
		(fp_line
			(start 0.2794 0.9906)
			(end -0.2794 0.9906)
			(stroke
				(width 0.1)
				(type default)
			)
			(layer "B.Fab")
		)
		(fp_line
			(start -0.2794 0.9906)
			(end -0.2794 -0.1016)
			(stroke
				(width 0.1)
				(type default)
			)
			(layer "B.Fab")
		)
		(pad "1" smd rect
			(at 0 0 270)
			(size 0.508 0.508)
			(layers "B.Cu" "B.Mask" "B.Paste")
			(net "H_CPU1_KLM_MEMHOT_LVT3_R_N")
		)
		(pad "2" smd rect
			(at 0 0.889 270)
			(size 0.508 0.508)
			(layers "B.Cu" "B.Mask" "B.Paste")
			(net "H_CPU1_MEMKLM_MEMHOT_LVT3_K_N")
		)
		(zone
			(layer "B.Cu")
			(hatch none 0.5)
			(connect_pads
				(clearance 0)
			)
			(min_thickness 0.25)
			(keepout
				(tracks allowed)
				(vias not_allowed)
				(pads allowed)
				(copperpour not_allowed)
				(footprints allowed)
			)
			(placement
				(enabled no)
				(sheetname "")
			)
			(fill
				(thermal_gap 0.5)
				(thermal_bridge_width 0.5)
				(island_removal_mode 0)
			)
			(polygon
				(pts
					(xy 434.0225 -17.653) (xy 434.0225 -17.145) (xy 434.4035 -17.145) (xy 434.4035 -17.653)
				)
			)
		)
		(zone
			(layer "B.Cu")
			(hatch none 0.5)
			(connect_pads
				(clearance 0)
			)
			(min_thickness 0.25)
			(keepout
				(tracks not_allowed)
				(vias allowed)
				(pads allowed)
				(copperpour not_allowed)
				(footprints allowed)
			)
			(placement
				(enabled no)
				(sheetname "")
			)
			(fill
				(thermal_gap 0.5)
				(thermal_bridge_width 0.5)
				(island_removal_mode 0)
			)
			(polygon
				(pts
					(xy 434.4035 -17.653) (xy 434.4035 -17.145) (xy 434.0225 -17.145) (xy 434.0225 -17.653)
				)
			)
		)
	)
	(footprint ""
		(layer "B.Cu")
		(at 465.595208 -147.955254 180)
		(property "Reference" "R1L13"
			(at 0 0 0)
			(layer "B.SilkS")
			(hide yes)
			(effects
				(font
					(size 1.27 1.27)
				)
				(justify mirror)
			)
		)
		(property "Value" ""
			(at 0 0 0)
			(layer "B.Fab")
			(effects
				(font
					(size 1.27 1.27)
				)
				(justify mirror)
			)
		)
		(duplicate_pad_numbers_are_jumpers no)
		(fp_poly
			(pts
				(xy 0.2794 -0.1016) (xy -0.2794 -0.1016) (xy -0.2794 0.9906) (xy 0.2794 0.9906)
			)
			(stroke
				(width 0)
				(type default)
			)
			(fill no)
			(layer "B.CrtYd")
		)
		(fp_line
			(start 0.2794 0.9906)
			(end -0.2794 0.9906)
			(stroke
				(width 0.1)
				(type default)
			)
			(layer "B.Fab")
		)
		(fp_line
			(start 0.2794 -0.1016)
			(end 0.2794 0.9906)
			(stroke
				(width 0.1)
				(type default)
			)
			(layer "B.Fab")
		)
		(fp_line
			(start -0.2794 0.9906)
			(end -0.2794 -0.1016)
			(stroke
				(width 0.1)
				(type default)
			)
			(layer "B.Fab")
		)
		(fp_line
			(start -0.2794 -0.1016)
			(end 0.2794 -0.1016)
			(stroke
				(width 0.1)
				(type default)
			)
			(layer "B.Fab")
		)
		(pad "1" smd rect
			(at 0 0)
			(size 0.508 0.508)
			(layers "B.Cu" "B.Mask" "B.Paste")
			(net "XDP_SYSPWROK")
		)
		(pad "2" smd rect
			(at 0 0.889)
			(size 0.508 0.508)
			(layers "B.Cu" "B.Mask" "B.Paste")
			(net "P3V3_STBY")
		)
		(zone
			(layer "B.Cu")
			(hatch none 0.5)
			(connect_pads
				(clearance 0)
			)
			(min_thickness 0.25)
			(keepout
				(tracks not_allowed)
				(vias allowed)
				(pads allowed)
				(copperpour not_allowed)
				(footprints allowed)
			)
			(placement
				(enabled no)
				(sheetname "")
			)
			(fill
				(thermal_gap 0.5)
				(thermal_bridge_width 0.5)
				(island_removal_mode 0)
			)
			(polygon
				(pts
					(xy 465.341208 -148.590254) (xy 465.849208 -148.590254) (xy 465.849208 -148.209254) (xy 465.341208 -148.209254)
				)
			)
		)
		(zone
			(layer "B.Cu")
			(hatch none 0.5)
			(connect_pads
				(clearance 0)
			)
			(min_thickness 0.25)
			(keepout
				(tracks allowed)
				(vias not_allowed)
				(pads allowed)
				(copperpour not_allowed)
				(footprints allowed)
			)
			(placement
				(enabled no)
				(sheetname "")
			)
			(fill
				(thermal_gap 0.5)
				(thermal_bridge_width 0.5)
				(island_removal_mode 0)
			)
			(polygon
				(pts
					(xy 465.341208 -148.209254) (xy 465.849208 -148.209254) (xy 465.849208 -148.590254) (xy 465.341208 -148.590254)
				)
			)
		)
	)
)
